(kicad_pcb
	(version 20260206)
	(generator "pcbnew")
	(generator_version "10.0")
	(general
		(thickness 1.6)
		(legacy_teardrops no)
	)
	(paper "A4")
	(title_block
		(title "Bryce Canyon_SCC_16316-1_OCP.brd")
		(comment 1 "Bryce Canyon / footprints 1258-1265 of 1561")
	)
	(layers
		(0 "F.Cu" signal "TOP")
		(4 "In1.Cu" signal "L2GND")
		(6 "In2.Cu" signal "L3")
		(8 "In3.Cu" signal "L4VCC")
		(10 "In4.Cu" signal "L5VCC")
		(12 "In5.Cu" signal "L6")
		(14 "In6.Cu" signal "L7GND")
		(2 "B.Cu" signal "BOTTOM")
		(9 "F.Adhes" user "F.Adhesive")
		(11 "B.Adhes" user "B.Adhesive")
		(13 "F.Paste" user "Package Geometry/Pastemask Top")
		(15 "B.Paste" user "Package Geometry/Pastemask Bottom")
		(5 "F.SilkS" user "Ref Des/Silkscreen Top")
		(7 "B.SilkS" user "Ref Des/Silkscreen Bottom")
		(1 "F.Mask" user "Board Geometry/Soldermask Top")
		(3 "B.Mask" user "Board Geometry/Soldermask Bottom")
		(17 "Dwgs.User" user "User.Drawings")
		(19 "Cmts.User" user "User.Comments")
		(21 "Eco1.User" user "User.Eco1")
		(23 "Eco2.User" user "User.Eco2")
		(25 "Edge.Cuts" user "Board Geometry/Outline")
		(27 "Margin" user)
		(31 "F.CrtYd" user "Package Geometry/Place Bound Top")
		(29 "B.CrtYd" user "Package Geometry/Place Bound Bottom")
		(35 "F.Fab" user "Ref Des/Assembly Top")
		(33 "B.Fab" user "Ref Des/Assembly Bottom")
	)
	(footprint ""
		(layer "B.Cu")
		(at 164.723318 -29.492956 -90)
		(property "Reference" "C398"
			(at 0 0 90)
			(layer "B.SilkS")
			(hide yes)
			(effects
				(font
					(size 1.27 1.27)
				)
				(justify mirror)
			)
		)
		(property "Value" "SCD1U16V2KX-3GP"
			(at -1.1811 -2.7051 270)
			(unlocked yes)
			(layer "B.Fab")
			(hide yes)
			(effects
				(font
					(size 1.016 1.016)
					(thickness 0.1524)
				)
				(justify mirror)
			)
		)
		(property "Device Type" "C402H22"
			(at -1.1811 -4.2291 270)
			(unlocked yes)
			(layer "B.Fab")
			(hide yes)
			(effects
				(font
					(size 1.016 1.016)
					(thickness 0.1524)
				)
				(justify mirror)
			)
		)
		(duplicate_pad_numbers_are_jumpers no)
		(fp_rect
			(start 0.4318 0.9525)
			(end -0.4318 -0.9525)
			(stroke
				(width 0)
				(type default)
			)
			(fill no)
			(layer "B.CrtYd")
		)
		(fp_rect
			(start 0.4318 0.9525)
			(end -0.4318 -0.9525)
			(stroke
				(width 0)
				(type default)
			)
			(fill no)
			(layer "B.Fab")
		)
		(pad "1" smd custom
			(at 0 -0.4445 90)
			(size 0.1524 0.1524)
			(layers "B.Cu" "B.Mask" "B.Paste")
			(net "SAS0_AVDD")
			(options
				(clearance outline)
				(anchor circle)
			)
			(primitives
				(gr_poly
					(pts
						(arc
							(start 0.3048 0.2032)
							(mid 0.275042 0.275042)
							(end 0.2032 0.3048)
						)
						(arc
							(start -0.2032 0.3048)
							(mid -0.275042 0.275042)
							(end -0.3048 0.2032)
						)
						(arc
							(start -0.3048 -0.2032)
							(mid -0.275042 -0.275042)
							(end -0.2032 -0.3048)
						)
						(arc
							(start 0.2032 -0.3048)
							(mid 0.275042 -0.275042)
							(end 0.3048 -0.2032)
						)
					)
					(width 0)
					(fill yes)
				)
			)
		)
		(pad "2" smd custom
			(at 0 0.4445 90)
			(size 0.1524 0.1524)
			(layers "B.Cu" "B.Mask" "B.Paste")
			(net "GND")
			(options
				(clearance outline)
				(anchor circle)
			)
			(primitives
				(gr_poly
					(pts
						(arc
							(start 0.3048 0.2032)
							(mid 0.275042 0.275042)
							(end 0.2032 0.3048)
						)
						(arc
							(start -0.2032 0.3048)
							(mid -0.275042 0.275042)
							(end -0.3048 0.2032)
						)
						(arc
							(start -0.3048 -0.2032)
							(mid -0.275042 -0.275042)
							(end -0.2032 -0.3048)
						)
						(arc
							(start 0.2032 -0.3048)
							(mid 0.275042 -0.275042)
							(end 0.3048 -0.2032)
						)
					)
					(width 0)
					(fill yes)
				)
			)
		)
	)
	(footprint ""
		(layer "B.Cu")
		(at 124.2695 -61.5061 -90)
		(property "Reference" "C592"
			(at 0 0 90)
			(layer "B.SilkS")
			(hide yes)
			(effects
				(font
					(size 1.27 1.27)
				)
				(justify mirror)
			)
		)
		(property "Value" "SCD1U6D3V1KX-GP"
			(at 2.8321 -1.7399 270)
			(unlocked yes)
			(layer "B.Fab")
			(hide yes)
			(effects
				(font
					(size 1.016 1.016)
					(thickness 0.1524)
				)
				(justify mirror)
			)
		)
		(property "Device Type" "C0201H13"
			(at 2.8321 -3.2639 270)
			(unlocked yes)
			(layer "B.Fab")
			(hide yes)
			(effects
				(font
					(size 1.016 1.016)
					(thickness 0.1524)
				)
				(justify mirror)
			)
		)
		(duplicate_pad_numbers_are_jumpers no)
		(fp_rect
			(start 0.2794 0.6477)
			(end -0.2794 -0.6477)
			(stroke
				(width 0)
				(type default)
			)
			(fill no)
			(layer "B.CrtYd")
		)
		(fp_rect
			(start 0.2794 0.6477)
			(end -0.2794 -0.6477)
			(stroke
				(width 0)
				(type default)
			)
			(fill no)
			(layer "B.Fab")
		)
		(pad "1" smd custom
			(at 0 -0.2794 90)
			(size 0.0762 0.0762)
			(layers "B.Cu" "B.Mask" "B.Paste")
			(net "GB_VDDA")
			(options
				(clearance outline)
				(anchor circle)
			)
			(primitives
				(gr_poly
					(pts
						(arc
							(start 0.1524 0.127)
							(mid 0.137521 0.162921)
							(end 0.1016 0.1778)
						)
						(arc
							(start -0.1016 0.1778)
							(mid -0.137521 0.162921)
							(end -0.1524 0.127)
						)
						(arc
							(start -0.1524 -0.127)
							(mid -0.137521 -0.162921)
							(end -0.1016 -0.1778)
						)
						(arc
							(start 0.1016 -0.1778)
							(mid 0.137521 -0.162921)
							(end 0.1524 -0.127)
						)
					)
					(width 0)
					(fill yes)
				)
			)
		)
		(pad "2" smd custom
			(at 0 0.2794 90)
			(size 0.0762 0.0762)
			(layers "B.Cu" "B.Mask" "B.Paste")
			(net "GND")
			(options
				(clearance outline)
				(anchor circle)
			)
			(primitives
				(gr_poly
					(pts
						(arc
							(start 0.1524 0.127)
							(mid 0.137521 0.162921)
							(end 0.1016 0.1778)
						)
						(arc
							(start -0.1016 0.1778)
							(mid -0.137521 0.162921)
							(end -0.1524 0.127)
						)
						(arc
							(start -0.1524 -0.127)
							(mid -0.137521 -0.162921)
							(end -0.1016 -0.1778)
						)
						(arc
							(start 0.1016 -0.1778)
							(mid 0.137521 -0.162921)
							(end 0.1524 -0.127)
						)
					)
					(width 0)
					(fill yes)
				)
			)
		)
	)
	(footprint ""
		(layer "B.Cu")
		(at 117.3988 -59.4487)
		(property "Reference" "C588"
			(at 0 0 0)
			(layer "B.SilkS")
			(hide yes)
			(effects
				(font
					(size 1.27 1.27)
				)
				(justify mirror)
			)
		)
		(property "Value" "SCD1U6D3V1KX-GP"
			(at 2.8321 -1.7399 0)
			(unlocked yes)
			(layer "B.Fab")
			(hide yes)
			(effects
				(font
					(size 1.016 1.016)
					(thickness 0.1524)
				)
				(justify mirror)
			)
		)
		(property "Device Type" "C0201H13"
			(at 2.8321 -3.2639 0)
			(unlocked yes)
			(layer "B.Fab")
			(hide yes)
			(effects
				(font
					(size 1.016 1.016)
					(thickness 0.1524)
				)
				(justify mirror)
			)
		)
		(duplicate_pad_numbers_are_jumpers no)
		(fp_rect
			(start 0.2794 0.6477)
			(end -0.2794 -0.6477)
			(stroke
				(width 0)
				(type default)
			)
			(fill no)
			(layer "B.CrtYd")
		)
		(fp_rect
			(start 0.2794 0.6477)
			(end -0.2794 -0.6477)
			(stroke
				(width 0)
				(type default)
			)
			(fill no)
			(layer "B.Fab")
		)
		(pad "1" smd custom
			(at 0 -0.2794 180)
			(size 0.0762 0.0762)
			(layers "B.Cu" "B.Mask" "B.Paste")
			(net "GB_VDDA")
			(options
				(clearance outline)
				(anchor circle)
			)
			(primitives
				(gr_poly
					(pts
						(arc
							(start 0.1524 0.127)
							(mid 0.137521 0.162921)
							(end 0.1016 0.1778)
						)
						(arc
							(start -0.1016 0.1778)
							(mid -0.137521 0.162921)
							(end -0.1524 0.127)
						)
						(arc
							(start -0.1524 -0.127)
							(mid -0.137521 -0.162921)
							(end -0.1016 -0.1778)
						)
						(arc
							(start 0.1016 -0.1778)
							(mid 0.137521 -0.162921)
							(end 0.1524 -0.127)
						)
					)
					(width 0)
					(fill yes)
				)
			)
		)
		(pad "2" smd custom
			(at 0 0.2794 180)
			(size 0.0762 0.0762)
			(layers "B.Cu" "B.Mask" "B.Paste")
			(net "GND")
			(options
				(clearance outline)
				(anchor circle)
			)
			(primitives
				(gr_poly
					(pts
						(arc
							(start 0.1524 0.127)
							(mid 0.137521 0.162921)
							(end 0.1016 0.1778)
						)
						(arc
							(start -0.1016 0.1778)
							(mid -0.137521 0.162921)
							(end -0.1524 0.127)
						)
						(arc
							(start -0.1524 -0.127)
							(mid -0.137521 -0.162921)
							(end -0.1016 -0.1778)
						)
						(arc
							(start 0.1016 -0.1778)
							(mid 0.137521 -0.162921)
							(end 0.1524 -0.127)
						)
					)
					(width 0)
					(fill yes)
				)
			)
		)
	)
	(footprint ""
		(layer "B.Cu")
		(at 174.371 -53.3908 90)
		(property "Reference" "R497"
			(at 0 0 90)
			(layer "B.SilkS")
			(hide yes)
			(effects
				(font
					(size 1.27 1.27)
				)
				(justify mirror)
			)
		)
		(property "Value" "0R2J-2-GP"
			(at -0.064008 -3.993896 90)
			(unlocked yes)
			(layer "B.Fab")
			(hide yes)
			(effects
				(font
					(size 1.016 1.016)
					(thickness 0.1524)
				)
				(justify mirror)
			)
		)
		(property "Device Type" "R402H16"
			(at -0.064008 -5.517896 90)
			(unlocked yes)
			(layer "B.Fab")
			(hide yes)
			(effects
				(font
					(size 1.016 1.016)
					(thickness 0.1524)
				)
				(justify mirror)
			)
		)
		(duplicate_pad_numbers_are_jumpers no)
		(fp_line
			(start 0.508 -0.9398)
			(end 0.508 0.9398)
			(stroke
				(width 0.1524)
				(type default)
			)
			(layer "B.SilkS")
		)
		(fp_line
			(start -0.508 -0.9398)
			(end 0.508 -0.9398)
			(stroke
				(width 0.1524)
				(type default)
			)
			(layer "B.SilkS")
		)
		(fp_rect
			(start 0.508 0.9398)
			(end -0.508 -0.9398)
			(stroke
				(width 0)
				(type default)
			)
			(fill no)
			(layer "B.CrtYd")
		)
		(fp_rect
			(start 0.508 0.9398)
			(end -0.508 -0.9398)
			(stroke
				(width 0)
				(type default)
			)
			(fill no)
			(layer "B.Fab")
		)
		(pad "1" smd custom
			(at 0 -0.4445 270)
			(size 0.1397 0.1397)
			(layers "B.Cu" "B.Mask" "B.Paste")
			(net "P0V975")
			(options
				(clearance outline)
				(anchor circle)
			)
			(primitives
				(gr_poly
					(pts
						(arc
							(start -0.1778 0.2794)
							(mid -0.249642 0.249642)
							(end -0.2794 0.1778)
						)
						(arc
							(start -0.2794 -0.1778)
							(mid -0.249642 -0.249642)
							(end -0.1778 -0.2794)
						)
						(arc
							(start 0.1778 -0.2794)
							(mid 0.249642 -0.249642)
							(end 0.2794 -0.1778)
						)
						(arc
							(start 0.2794 0.1778)
							(mid 0.249642 0.249642)
							(end 0.1778 0.2794)
						)
					)
					(width 0)
					(fill yes)
				)
			)
		)
		(pad "2" smd custom
			(at 0 0.4445 270)
			(size 0.1397 0.1397)
			(layers "B.Cu" "B.Mask" "B.Paste")
			(net "P0V975_SEN")
			(options
				(clearance outline)
				(anchor circle)
			)
			(primitives
				(gr_poly
					(pts
						(arc
							(start -0.1778 0.2794)
							(mid -0.249642 0.249642)
							(end -0.2794 0.1778)
						)
						(arc
							(start -0.2794 -0.1778)
							(mid -0.249642 -0.249642)
							(end -0.1778 -0.2794)
						)
						(arc
							(start 0.1778 -0.2794)
							(mid 0.249642 -0.249642)
							(end 0.2794 -0.1778)
						)
						(arc
							(start 0.2794 0.1778)
							(mid 0.249642 0.249642)
							(end 0.1778 0.2794)
						)
					)
					(width 0)
					(fill yes)
				)
			)
		)
	)
	(footprint ""
		(layer "B.Cu")
		(at 181.229 -30.353 -90)
		(property "Reference" "C487"
			(at 0 0 90)
			(layer "B.SilkS")
			(hide yes)
			(effects
				(font
					(size 1.27 1.27)
				)
				(justify mirror)
			)
		)
		(property "Value" "SC1U16V2KX-7-GP"
			(at -1.7526 -1.6002 270)
			(unlocked yes)
			(layer "B.Fab")
			(hide yes)
			(effects
				(font
					(size 1.016 1.016)
					(thickness 0.1524)
				)
				(justify mirror)
			)
		)
		(property "Device Type" "C402-TO0D2H24"
			(at -1.7526 -3.1242 270)
			(unlocked yes)
			(layer "B.Fab")
			(hide yes)
			(effects
				(font
					(size 1.016 1.016)
					(thickness 0.1524)
				)
				(justify mirror)
			)
		)
		(duplicate_pad_numbers_are_jumpers no)
		(fp_rect
			(start 0.4826 0.889)
			(end -0.4826 -0.889)
			(stroke
				(width 0)
				(type default)
			)
			(fill no)
			(layer "B.CrtYd")
		)
		(fp_rect
			(start 0.4826 0.889)
			(end -0.4826 -0.889)
			(stroke
				(width 0)
				(type default)
			)
			(fill no)
			(layer "B.Fab")
		)
		(pad "1" smd custom
			(at 0 -0.4572 90)
			(size 0.1524 0.1524)
			(layers "B.Cu" "B.Mask" "B.Paste")
			(net "P1V8_C")
			(options
				(clearance outline)
				(anchor circle)
			)
			(primitives
				(gr_poly
					(pts
						(arc
							(start -0.254 -0.3048)
							(mid -0.325842 -0.275042)
							(end -0.3556 -0.2032)
						)
						(arc
							(start -0.3556 0.2032)
							(mid -0.325842 0.275042)
							(end -0.254 0.3048)
						)
						(arc
							(start 0.254 0.3048)
							(mid 0.325842 0.275042)
							(end 0.3556 0.2032)
						)
						(arc
							(start 0.3556 -0.2032)
							(mid 0.325842 -0.275042)
							(end 0.254 -0.3048)
						)
					)
					(width 0)
					(fill yes)
				)
			)
		)
		(pad "2" smd custom
			(at 0 0.4572 90)
			(size 0.1524 0.1524)
			(layers "B.Cu" "B.Mask" "B.Paste")
			(net "GND")
			(options
				(clearance outline)
				(anchor circle)
			)
			(primitives
				(gr_poly
					(pts
						(arc
							(start -0.254 -0.3048)
							(mid -0.325842 -0.275042)
							(end -0.3556 -0.2032)
						)
						(arc
							(start -0.3556 0.2032)
							(mid -0.325842 0.275042)
							(end -0.254 0.3048)
						)
						(arc
							(start 0.254 0.3048)
							(mid 0.325842 0.275042)
							(end 0.3556 0.2032)
						)
						(arc
							(start 0.3556 -0.2032)
							(mid 0.325842 -0.275042)
							(end 0.254 -0.3048)
						)
					)
					(width 0)
					(fill yes)
				)
			)
		)
	)
	(footprint ""
		(layer "B.Cu")
		(at 184.155588 -32.230314 90)
		(property "Reference" "C467"
			(at 0 0 90)
			(layer "B.SilkS")
			(hide yes)
			(effects
				(font
					(size 1.27 1.27)
				)
				(justify mirror)
			)
		)
		(property "Value" "SCD1U6D3V1KX-GP"
			(at 2.8321 -1.7399 90)
			(unlocked yes)
			(layer "B.Fab")
			(hide yes)
			(effects
				(font
					(size 1.016 1.016)
					(thickness 0.1524)
				)
				(justify mirror)
			)
		)
		(property "Device Type" "C0201H13"
			(at 2.8321 -3.2639 90)
			(unlocked yes)
			(layer "B.Fab")
			(hide yes)
			(effects
				(font
					(size 1.016 1.016)
					(thickness 0.1524)
				)
				(justify mirror)
			)
		)
		(duplicate_pad_numbers_are_jumpers no)
		(fp_rect
			(start 0.2794 0.6477)
			(end -0.2794 -0.6477)
			(stroke
				(width 0)
				(type default)
			)
			(fill no)
			(layer "B.CrtYd")
		)
		(fp_rect
			(start 0.2794 0.6477)
			(end -0.2794 -0.6477)
			(stroke
				(width 0)
				(type default)
			)
			(fill no)
			(layer "B.Fab")
		)
		(pad "1" smd custom
			(at 0 -0.2794 270)
			(size 0.0762 0.0762)
			(layers "B.Cu" "B.Mask" "B.Paste")
			(net "P1V8_C")
			(options
				(clearance outline)
				(anchor circle)
			)
			(primitives
				(gr_poly
					(pts
						(arc
							(start 0.1524 0.127)
							(mid 0.137521 0.162921)
							(end 0.1016 0.1778)
						)
						(arc
							(start -0.1016 0.1778)
							(mid -0.137521 0.162921)
							(end -0.1524 0.127)
						)
						(arc
							(start -0.1524 -0.127)
							(mid -0.137521 -0.162921)
							(end -0.1016 -0.1778)
						)
						(arc
							(start 0.1016 -0.1778)
							(mid 0.137521 -0.162921)
							(end 0.1524 -0.127)
						)
					)
					(width 0)
					(fill yes)
				)
			)
		)
		(pad "2" smd custom
			(at 0 0.2794 270)
			(size 0.0762 0.0762)
			(layers "B.Cu" "B.Mask" "B.Paste")
			(net "GND")
			(options
				(clearance outline)
				(anchor circle)
			)
			(primitives
				(gr_poly
					(pts
						(arc
							(start 0.1524 0.127)
							(mid 0.137521 0.162921)
							(end 0.1016 0.1778)
						)
						(arc
							(start -0.1016 0.1778)
							(mid -0.137521 0.162921)
							(end -0.1524 0.127)
						)
						(arc
							(start -0.1524 -0.127)
							(mid -0.137521 -0.162921)
							(end -0.1016 -0.1778)
						)
						(arc
							(start 0.1016 -0.1778)
							(mid 0.137521 -0.162921)
							(end 0.1524 -0.127)
						)
					)
					(width 0)
					(fill yes)
				)
			)
		)
	)
	(footprint ""
		(layer "B.Cu")
		(at 124.2822 -68.5038 -90)
		(property "Reference" "C245"
			(at 0 0 90)
			(layer "B.SilkS")
			(hide yes)
			(effects
				(font
					(size 1.27 1.27)
				)
				(justify mirror)
			)
		)
		(property "Value" "SCD1U6D3V1KX-GP"
			(at 2.8321 -1.7399 270)
			(unlocked yes)
			(layer "B.Fab")
			(hide yes)
			(effects
				(font
					(size 1.016 1.016)
					(thickness 0.1524)
				)
				(justify mirror)
			)
		)
		(property "Device Type" "C0201H13"
			(at 2.8321 -3.2639 270)
			(unlocked yes)
			(layer "B.Fab")
			(hide yes)
			(effects
				(font
					(size 1.016 1.016)
					(thickness 0.1524)
				)
				(justify mirror)
			)
		)
		(duplicate_pad_numbers_are_jumpers no)
		(fp_rect
			(start 0.2794 0.6477)
			(end -0.2794 -0.6477)
			(stroke
				(width 0)
				(type default)
			)
			(fill no)
			(layer "B.CrtYd")
		)
		(fp_rect
			(start 0.2794 0.6477)
			(end -0.2794 -0.6477)
			(stroke
				(width 0)
				(type default)
			)
			(fill no)
			(layer "B.Fab")
		)
		(pad "1" smd custom
			(at 0 -0.2794 90)
			(size 0.0762 0.0762)
			(layers "B.Cu" "B.Mask" "B.Paste")
			(net "GB_VDDA")
			(options
				(clearance outline)
				(anchor circle)
			)
			(primitives
				(gr_poly
					(pts
						(arc
							(start 0.1524 0.127)
							(mid 0.137521 0.162921)
							(end 0.1016 0.1778)
						)
						(arc
							(start -0.1016 0.1778)
							(mid -0.137521 0.162921)
							(end -0.1524 0.127)
						)
						(arc
							(start -0.1524 -0.127)
							(mid -0.137521 -0.162921)
							(end -0.1016 -0.1778)
						)
						(arc
							(start 0.1016 -0.1778)
							(mid 0.137521 -0.162921)
							(end 0.1524 -0.127)
						)
					)
					(width 0)
					(fill yes)
				)
			)
		)
		(pad "2" smd custom
			(at 0 0.2794 90)
			(size 0.0762 0.0762)
			(layers "B.Cu" "B.Mask" "B.Paste")
			(net "GND")
			(options
				(clearance outline)
				(anchor circle)
			)
			(primitives
				(gr_poly
					(pts
						(arc
							(start 0.1524 0.127)
							(mid 0.137521 0.162921)
							(end 0.1016 0.1778)
						)
						(arc
							(start -0.1016 0.1778)
							(mid -0.137521 0.162921)
							(end -0.1524 0.127)
						)
						(arc
							(start -0.1524 -0.127)
							(mid -0.137521 -0.162921)
							(end -0.1016 -0.1778)
						)
						(arc
							(start 0.1016 -0.1778)
							(mid 0.137521 -0.162921)
							(end 0.1524 -0.127)
						)
					)
					(width 0)
					(fill yes)
				)
			)
		)
	)
	(footprint ""
		(layer "B.Cu")
		(at 127.3556 -85.344)
		(property "Reference" "TP158"
			(at 0 0 0)
			(layer "B.SilkS")
			(hide yes)
			(effects
				(font
					(size 1.27 1.27)
				)
				(justify mirror)
			)
		)
		(property "Value" "TPAD28-2-GP"
			(at 0.0127 -1.6637 0)
			(unlocked yes)
			(layer "B.Fab")
			(hide yes)
			(effects
				(font
					(size 1.016 1.016)
					(thickness 0.1524)
				)
				(justify mirror)
			)
		)
		(property "Device Type" "TPAD28"
			(at 0.0127 -3.1877 0)
			(unlocked yes)
			(layer "B.Fab")
			(hide yes)
			(effects
				(font
					(size 1.016 1.016)
					(thickness 0.1524)
				)
				(justify mirror)
			)
		)
		(duplicate_pad_numbers_are_jumpers no)
		(fp_poly
			(pts
				(arc
					(start 0.3556 0)
					(mid -0.3556 0)
					(end 0.3556 0)
				)
			)
			(stroke
				(width 0)
				(type default)
			)
			(fill no)
			(layer "B.CrtYd")
		)
		(fp_poly
			(pts
				(arc
					(start 0.6096 0)
					(mid -0.6096 0)
					(end 0.6096 0)
				)
			)
			(stroke
				(width 0)
				(type default)
			)
			(fill no)
			(layer "B.Fab")
		)
		(pad "1" smd circle
			(at 0 0 180)
			(size 0.7112 0.7112)
			(layers "B.Cu" "B.Mask" "B.Paste")
			(net "ICE_TDI")
		)
	)
)
